(kicad_pcb
	(version 20260206)
	(generator "pcbnew")
	(generator_version "10.0")
	(general
		(thickness 1.6)
		(legacy_teardrops no)
	)
	(paper "A4")
	(title_block
		(title "04192023_DAF0TMB3IC0_F0TG_MB_C_brd_V02_OCP.brd")
		(comment 1 "Grand Teton / footprints 8183-8189 of 8354")
	)
	(layers
		(0 "F.Cu" signal "TOP")
		(4 "In1.Cu" signal "GND")
		(6 "In2.Cu" signal "IN1")
		(8 "In3.Cu" signal "GND1")
		(10 "In4.Cu" signal "IN2")
		(12 "In5.Cu" signal "GND2")
		(14 "In6.Cu" signal "IN3")
		(16 "In7.Cu" signal "GND3")
		(18 "In8.Cu" signal "VCC")
		(20 "In9.Cu" signal "VCC1")
		(22 "In10.Cu" signal "GND4")
		(24 "In11.Cu" signal "IN4")
		(26 "In12.Cu" signal "GND5")
		(28 "In13.Cu" signal "IN5")
		(30 "In14.Cu" signal "GND6")
		(32 "In15.Cu" signal "IN6")
		(34 "In16.Cu" signal "GND7")
		(2 "B.Cu" signal "BOTTOM")
		(9 "F.Adhes" user "F.Adhesive")
		(11 "B.Adhes" user "B.Adhesive")
		(13 "F.Paste" user "Package Geometry/Pastemask Top")
		(15 "B.Paste" user "Package Geometry/Pastemask Bottom")
		(5 "F.SilkS" user "Ref Des/Silkscreen Top")
		(7 "B.SilkS" user "Ref Des/Silkscreen Bottom")
		(1 "F.Mask" user "Board Geometry/Soldermask Top")
		(3 "B.Mask" user "Board Geometry/Soldermask Bottom")
		(17 "Dwgs.User" user "User.Drawings")
		(19 "Cmts.User" user "User.Comments")
		(21 "Eco1.User" user "User.Eco1")
		(23 "Eco2.User" user "User.Eco2")
		(25 "Edge.Cuts" user "Board Geometry/Outline")
		(27 "Margin" user)
		(31 "F.CrtYd" user "Package Geometry/Place Bound Top")
		(29 "B.CrtYd" user "Package Geometry/Place Bound Bottom")
		(35 "F.Fab" user "Ref Des/Assembly Top")
		(33 "B.Fab" user "Ref Des/Assembly Bottom")
	)
	(footprint ""
		(layer "B.Cu")
		(at 373.424958 -268.855952 60)
		(property "Reference" "C2246"
			(at 0 0 60)
			(layer "B.SilkS")
			(hide yes)
			(effects
				(font
					(size 1.27 1.27)
				)
				(justify mirror)
			)
		)
		(property "Value" ""
			(at 0 0 60)
			(layer "B.Fab")
			(effects
				(font
					(size 1.27 1.27)
				)
				(justify mirror)
			)
		)
		(duplicate_pad_numbers_are_jumpers no)
		(fp_line
			(start -0.787516 -0.406438)
			(end -0.787425 0.40652)
			(stroke
				(width 0.1524)
				(type default)
			)
			(layer "B.SilkS")
		)
		(fp_line
			(start -0.787425 0.40652)
			(end 0.787516 0.406438)
			(stroke
				(width 0.1524)
				(type default)
			)
			(layer "B.SilkS")
		)
		(fp_line
			(start 0.787425 -0.40652)
			(end -0.787516 -0.406438)
			(stroke
				(width 0.1524)
				(type default)
			)
			(layer "B.SilkS")
		)
		(fp_line
			(start 0.787516 0.406438)
			(end 0.787425 -0.40652)
			(stroke
				(width 0.1524)
				(type default)
			)
			(layer "B.SilkS")
		)
		(fp_line
			(start -0.679568 -0.304811)
			(end -0.6795 0.304908)
			(stroke
				(width 0.1)
				(type default)
			)
			(layer "B.Fab")
		)
		(fp_line
			(start -0.120605 -0.304905)
			(end -0.679568 -0.304811)
			(stroke
				(width 0.1)
				(type default)
			)
			(layer "B.Fab")
		)
		(fp_line
			(start -0.120554 -0.279418)
			(end -0.120605 -0.304905)
			(stroke
				(width 0.1)
				(type default)
			)
			(layer "B.Fab")
		)
		(fp_line
			(start 0.120629 -0.30516)
			(end 0.120587 -0.279326)
			(stroke
				(width 0.1)
				(type default)
			)
			(layer "B.Fab")
		)
		(fp_line
			(start 0.120587 -0.279326)
			(end -0.120554 -0.279418)
			(stroke
				(width 0.1)
				(type default)
			)
			(layer "B.Fab")
		)
		(fp_line
			(start -0.6795 0.304908)
			(end -0.120316 0.304686)
			(stroke
				(width 0.1)
				(type default)
			)
			(layer "B.Fab")
		)
		(fp_line
			(start 0.679373 -0.305128)
			(end 0.120629 -0.30516)
			(stroke
				(width 0.1)
				(type default)
			)
			(layer "B.Fab")
		)
		(fp_line
			(start -0.12024 0.279419)
			(end 0.120554 0.279418)
			(stroke
				(width 0.1)
				(type default)
			)
			(layer "B.Fab")
		)
		(fp_line
			(start -0.120316 0.304686)
			(end -0.12024 0.279419)
			(stroke
				(width 0.1)
				(type default)
			)
			(layer "B.Fab")
		)
		(fp_line
			(start 0.120554 0.279418)
			(end 0.120605 0.304905)
			(stroke
				(width 0.1)
				(type default)
			)
			(layer "B.Fab")
		)
		(fp_line
			(start 0.120605 0.304905)
			(end 0.679568 0.304811)
			(stroke
				(width 0.1)
				(type default)
			)
			(layer "B.Fab")
		)
		(fp_line
			(start 0.679568 0.304811)
			(end 0.679373 -0.305128)
			(stroke
				(width 0.1)
				(type default)
			)
			(layer "B.Fab")
		)
		(pad "1" smd circle
			(at 0.40005 0 240)
			(size 0 0)
			(layers "B.Cu" "B.Mask" "B.Paste")
			(net "PVDDCR_CPU1_P0")
		)
		(pad "2" smd circle
			(at -0.40005 0 240)
			(size 0 0)
			(layers "B.Cu" "B.Mask" "B.Paste")
			(net "GND")
		)
	)
	(footprint ""
		(layer "B.Cu")
		(at 440.153806 -21.932392)
		(property "Reference" "PC2080"
			(at 0 0 0)
			(layer "B.SilkS")
			(hide yes)
			(effects
				(font
					(size 1.27 1.27)
				)
				(justify mirror)
			)
		)
		(property "Value" ""
			(at 0 0 0)
			(layer "B.Fab")
			(effects
				(font
					(size 1.27 1.27)
				)
				(justify mirror)
			)
		)
		(duplicate_pad_numbers_are_jumpers no)
		(fp_line
			(start -1.524 -0.762)
			(end -1.524 0.762)
			(stroke
				(width 0.1524)
				(type default)
			)
			(layer "B.SilkS")
		)
		(fp_line
			(start -1.524 0.762)
			(end 1.524 0.762)
			(stroke
				(width 0.1524)
				(type default)
			)
			(layer "B.SilkS")
		)
		(fp_line
			(start 1.524 -0.762)
			(end -1.524 -0.762)
			(stroke
				(width 0.1524)
				(type default)
			)
			(layer "B.SilkS")
		)
		(fp_line
			(start 1.524 0.762)
			(end 1.524 -0.762)
			(stroke
				(width 0.1524)
				(type default)
			)
			(layer "B.SilkS")
		)
		(fp_line
			(start -1.1049 -0.724916)
			(end 1.1049 -0.724916)
			(stroke
				(width 0.1)
				(type default)
			)
			(layer "B.Fab")
		)
		(fp_line
			(start -1.1049 0.724916)
			(end -1.1049 -0.724916)
			(stroke
				(width 0.1)
				(type default)
			)
			(layer "B.Fab")
		)
		(fp_line
			(start 1.1049 -0.724916)
			(end 1.1049 0.724916)
			(stroke
				(width 0.1)
				(type default)
			)
			(layer "B.Fab")
		)
		(fp_line
			(start 1.1049 0.724916)
			(end -1.1049 0.724916)
			(stroke
				(width 0.1)
				(type default)
			)
			(layer "B.Fab")
		)
		(pad "1" smd rect
			(at 0.889 0)
			(size 1.016 1.27)
			(layers "B.Cu" "B.Mask" "B.Paste")
			(net "P12V_OCP_SFF")
		)
		(pad "2" smd rect
			(at -0.889 0)
			(size 1.016 1.27)
			(layers "B.Cu" "B.Mask" "B.Paste")
			(net "GND")
		)
	)
	(footprint ""
		(layer "B.Cu")
		(at 65.518538 -388.011162 -90)
		(property "Reference" "C253"
			(at 0 0 90)
			(layer "B.SilkS")
			(hide yes)
			(effects
				(font
					(size 1.27 1.27)
				)
				(justify mirror)
			)
		)
		(property "Value" ""
			(at 0 0 90)
			(layer "B.Fab")
			(effects
				(font
					(size 1.27 1.27)
				)
				(justify mirror)
			)
		)
		(duplicate_pad_numbers_are_jumpers no)
		(fp_line
			(start -0.299974 0.150114)
			(end 0.299974 0.150114)
			(stroke
				(width 0.1)
				(type default)
			)
			(layer "B.Fab")
		)
		(fp_line
			(start 0.299974 0.150114)
			(end 0.299974 -0.150114)
			(stroke
				(width 0.1)
				(type default)
			)
			(layer "B.Fab")
		)
		(fp_line
			(start -0.299974 -0.150114)
			(end -0.299974 0.150114)
			(stroke
				(width 0.1)
				(type default)
			)
			(layer "B.Fab")
		)
		(fp_line
			(start 0.299974 -0.150114)
			(end -0.299974 -0.150114)
			(stroke
				(width 0.1)
				(type default)
			)
			(layer "B.Fab")
		)
		(pad "1" smd rect
			(at 0.2667 0 90)
			(size 0.3048 0.381)
			(layers "B.Cu" "B.Mask" "B.Paste")
			(net "P0V9_CPU1_RT0_2A")
		)
		(pad "2" smd rect
			(at -0.2667 0 90)
			(size 0.3048 0.381)
			(layers "B.Cu" "B.Mask" "B.Paste")
			(net "GND")
		)
	)
	(footprint ""
		(layer "B.Cu")
		(at 338.560664 -73.534778)
		(property "Reference" "Q84"
			(at 1.4224 -1.768348 0)
			(unlocked yes)
			(layer "B.SilkS")
			(effects
				(font
					(size 0.7874 0.5842)
					(thickness 0.1524)
				)
				(justify left mirror)
			)
		)
		(property "Value" ""
			(at 0 0 0)
			(layer "B.Fab")
			(effects
				(font
					(size 1.27 1.27)
				)
				(justify mirror)
			)
		)
		(duplicate_pad_numbers_are_jumpers no)
		(fp_line
			(start -1.332738 -1.100074)
			(end -1.332738 1.100074)
			(stroke
				(width 0.1524)
				(type default)
			)
			(layer "B.SilkS")
		)
		(fp_line
			(start -1.332738 1.100074)
			(end 1.332738 1.100074)
			(stroke
				(width 0.1524)
				(type default)
			)
			(layer "B.SilkS")
		)
		(fp_line
			(start -0.4826 -1.100074)
			(end -1.332738 -1.100074)
			(stroke
				(width 0.1524)
				(type default)
			)
			(layer "B.SilkS")
		)
		(fp_line
			(start 0 -0.541274)
			(end -0.4826 -1.100074)
			(stroke
				(width 0.1524)
				(type default)
			)
			(layer "B.SilkS")
		)
		(fp_line
			(start 0.4826 -1.100074)
			(end 0 -0.541274)
			(stroke
				(width 0.1524)
				(type default)
			)
			(layer "B.SilkS")
		)
		(fp_line
			(start 1.332738 -1.100074)
			(end 0.4826 -1.100074)
			(stroke
				(width 0.1524)
				(type default)
			)
			(layer "B.SilkS")
		)
		(fp_line
			(start 1.332738 1.100074)
			(end 1.332738 -1.100074)
			(stroke
				(width 0.1524)
				(type default)
			)
			(layer "B.SilkS")
		)
		(fp_poly
			(pts
				(xy 1.378458 -0.627888) (xy 2.080514 -0.978916) (xy 2.080514 -0.27686)
			)
			(stroke
				(width 0)
				(type default)
			)
			(fill yes)
			(layer "B.SilkS")
		)
		(fp_line
			(start -0.674878 -1.100074)
			(end -0.674878 1.100074)
			(stroke
				(width 0.1)
				(type default)
			)
			(layer "B.Fab")
		)
		(fp_line
			(start -0.674878 1.100074)
			(end 0.674878 1.100074)
			(stroke
				(width 0.1)
				(type default)
			)
			(layer "B.Fab")
		)
		(fp_line
			(start 0.674878 -1.100074)
			(end -0.674878 -1.100074)
			(stroke
				(width 0.1)
				(type default)
			)
			(layer "B.Fab")
		)
		(fp_line
			(start 0.674878 1.100074)
			(end 0.674878 -1.100074)
			(stroke
				(width 0.1)
				(type default)
			)
			(layer "B.Fab")
		)
		(fp_poly
			(pts
				(xy 2.2352 -0.298958) (xy 2.2352 -1.001014) (xy 1.533144 -0.649986)
			)
			(stroke
				(width 0)
				(type default)
			)
			(fill yes)
			(layer "B.Fab")
		)
		(pad "1" smd rect
			(at 0.94996 -0.649986 90)
			(size 0.4318 0.508)
			(layers "B.Cu" "B.Mask" "B.Paste")
			(net "GND")
		)
		(pad "2" smd rect
			(at 0.94996 0 90)
			(size 0.4318 0.508)
			(layers "B.Cu" "B.Mask" "B.Paste")
			(net "FM_LED_PWRGD_PVDDCR_CPU0_P1")
		)
		(pad "3" smd rect
			(at 0.94996 0.649986 90)
			(size 0.4318 0.508)
			(layers "B.Cu" "B.Mask" "B.Paste")
			(net "LED_PWRGD_PVDDCR_SOC_P1_D")
		)
		(pad "4" smd rect
			(at -0.94996 0.649986 90)
			(size 0.4318 0.508)
			(layers "B.Cu" "B.Mask" "B.Paste")
			(net "GND")
		)
		(pad "5" smd rect
			(at -0.94996 0 90)
			(size 0.4318 0.508)
			(layers "B.Cu" "B.Mask" "B.Paste")
			(net "FM_LED_PWRGD_PVDDCR_SOC_P1")
		)
		(pad "6" smd rect
			(at -0.94996 -0.649986 90)
			(size 0.4318 0.508)
			(layers "B.Cu" "B.Mask" "B.Paste")
			(net "LED_PWRGD_PVDDCR_CPU0_P1_D")
		)
	)
	(footprint ""
		(layer "B.Cu")
		(at 366.36579 -393.96416 180)
		(property "Reference" "R1115"
			(at 0 0 0)
			(layer "B.SilkS")
			(hide yes)
			(effects
				(font
					(size 1.27 1.27)
				)
				(justify mirror)
			)
		)
		(property "Value" ""
			(at 0 0 0)
			(layer "B.Fab")
			(effects
				(font
					(size 1.27 1.27)
				)
				(justify mirror)
			)
		)
		(duplicate_pad_numbers_are_jumpers no)
		(fp_line
			(start 0.32512 0.175006)
			(end 0.32512 -0.175006)
			(stroke
				(width 0.1)
				(type default)
			)
			(layer "B.Fab")
		)
		(fp_line
			(start 0.32512 -0.175006)
			(end -0.32512 -0.175006)
			(stroke
				(width 0.1)
				(type default)
			)
			(layer "B.Fab")
		)
		(fp_line
			(start -0.32512 0.175006)
			(end 0.32512 0.175006)
			(stroke
				(width 0.1)
				(type default)
			)
			(layer "B.Fab")
		)
		(fp_line
			(start -0.32512 -0.175006)
			(end -0.32512 0.175006)
			(stroke
				(width 0.1)
				(type default)
			)
			(layer "B.Fab")
		)
		(pad "1" smd rect
			(at 0.2667 0)
			(size 0.3048 0.381)
			(layers "B.Cu" "B.Mask" "B.Paste")
			(net "TEST0_RT_CPU0_P3")
		)
		(pad "2" smd rect
			(at -0.2667 0 180)
			(size 0.3048 0.381)
			(layers "B.Cu" "B.Mask" "B.Paste")
			(net "GND")
		)
	)
	(footprint ""
		(layer "B.Cu")
		(at 367.614454 -264.35431)
		(property "Reference" "C2645"
			(at 0 0 0)
			(layer "B.SilkS")
			(hide yes)
			(effects
				(font
					(size 1.27 1.27)
				)
				(justify mirror)
			)
		)
		(property "Value" ""
			(at 0 0 0)
			(layer "B.Fab")
			(effects
				(font
					(size 1.27 1.27)
				)
				(justify mirror)
			)
		)
		(duplicate_pad_numbers_are_jumpers no)
		(fp_line
			(start -0.7874 -0.4064)
			(end -0.7874 0.4064)
			(stroke
				(width 0.1524)
				(type default)
			)
			(layer "B.SilkS")
		)
		(fp_line
			(start -0.7874 0.4064)
			(end 0.7874 0.4064)
			(stroke
				(width 0.1524)
				(type default)
			)
			(layer "B.SilkS")
		)
		(fp_line
			(start 0.7874 -0.4064)
			(end -0.7874 -0.4064)
			(stroke
				(width 0.1524)
				(type default)
			)
			(layer "B.SilkS")
		)
		(fp_line
			(start 0.7874 0.4064)
			(end 0.7874 -0.4064)
			(stroke
				(width 0.1524)
				(type default)
			)
			(layer "B.SilkS")
		)
		(fp_line
			(start -0.67945 -0.3048)
			(end -0.67945 0.3048)
			(stroke
				(width 0.1)
				(type default)
			)
			(layer "B.Fab")
		)
		(fp_line
			(start -0.67945 0.3048)
			(end -0.120396 0.3048)
			(stroke
				(width 0.1)
				(type default)
			)
			(layer "B.Fab")
		)
		(fp_line
			(start -0.12065 -0.3048)
			(end -0.67945 -0.3048)
			(stroke
				(width 0.1)
				(type default)
			)
			(layer "B.Fab")
		)
		(fp_line
			(start -0.12065 -0.2794)
			(end -0.12065 -0.3048)
			(stroke
				(width 0.1)
				(type default)
			)
			(layer "B.Fab")
		)
		(fp_line
			(start -0.120396 0.2794)
			(end 0.12065 0.2794)
			(stroke
				(width 0.1)
				(type default)
			)
			(layer "B.Fab")
		)
		(fp_line
			(start -0.120396 0.3048)
			(end -0.120396 0.2794)
			(stroke
				(width 0.1)
				(type default)
			)
			(layer "B.Fab")
		)
		(fp_line
			(start 0.12065 -0.305054)
			(end 0.12065 -0.2794)
			(stroke
				(width 0.1)
				(type default)
			)
			(layer "B.Fab")
		)
		(fp_line
			(start 0.12065 -0.2794)
			(end -0.12065 -0.2794)
			(stroke
				(width 0.1)
				(type default)
			)
			(layer "B.Fab")
		)
		(fp_line
			(start 0.12065 0.2794)
			(end 0.12065 0.3048)
			(stroke
				(width 0.1)
				(type default)
			)
			(layer "B.Fab")
		)
		(fp_line
			(start 0.12065 0.3048)
			(end 0.67945 0.3048)
			(stroke
				(width 0.1)
				(type default)
			)
			(layer "B.Fab")
		)
		(fp_line
			(start 0.67945 -0.305054)
			(end 0.12065 -0.305054)
			(stroke
				(width 0.1)
				(type default)
			)
			(layer "B.Fab")
		)
		(fp_line
			(start 0.67945 0.3048)
			(end 0.67945 -0.305054)
			(stroke
				(width 0.1)
				(type default)
			)
			(layer "B.Fab")
		)
		(pad "1" smd circle
			(at 0.40005 0 180)
			(size 0 0)
			(layers "B.Cu" "B.Mask" "B.Paste")
			(net "PVDD11_S3_P0")
		)
		(pad "2" smd circle
			(at -0.40005 0 180)
			(size 0 0)
			(layers "B.Cu" "B.Mask" "B.Paste")
			(net "GND")
		)
	)
	(footprint ""
		(layer "B.Cu")
		(at 232.918 -232.156 -90)
		(property "Reference" "R146"
			(at 0 0 90)
			(layer "B.SilkS")
			(hide yes)
			(effects
				(font
					(size 1.27 1.27)
				)
				(justify mirror)
			)
		)
		(property "Value" ""
			(at 0 0 90)
			(layer "B.Fab")
			(effects
				(font
					(size 1.27 1.27)
				)
				(justify mirror)
			)
		)
		(duplicate_pad_numbers_are_jumpers no)
		(fp_line
			(start -0.7874 0.4064)
			(end 0.7874 0.4064)
			(stroke
				(width 0.1524)
				(type default)
			)
			(layer "B.SilkS")
		)
		(fp_line
			(start 0.7874 0.4064)
			(end 0.7874 -0.4064)
			(stroke
				(width 0.1524)
				(type default)
			)
			(layer "B.SilkS")
		)
		(fp_line
			(start -0.7874 -0.4064)
			(end -0.7874 0.4064)
			(stroke
				(width 0.1524)
				(type default)
			)
			(layer "B.SilkS")
		)
		(fp_line
			(start 0.7874 -0.4064)
			(end -0.7874 -0.4064)
			(stroke
				(width 0.1524)
				(type default)
			)
			(layer "B.SilkS")
		)
		(fp_line
			(start -0.67945 0.3048)
			(end -0.120396 0.3048)
			(stroke
				(width 0.1)
				(type default)
			)
			(layer "B.Fab")
		)
		(fp_line
			(start -0.120396 0.3048)
			(end -0.120396 0.2794)
			(stroke
				(width 0.1)
				(type default)
			)
			(layer "B.Fab")
		)
		(fp_line
			(start 0.12065 0.3048)
			(end 0.67945 0.3048)
			(stroke
				(width 0.1)
				(type default)
			)
			(layer "B.Fab")
		)
		(fp_line
			(start 0.67945 0.3048)
			(end 0.67945 -0.305054)
			(stroke
				(width 0.1)
				(type default)
			)
			(layer "B.Fab")
		)
		(fp_line
			(start -0.120396 0.2794)
			(end 0.12065 0.2794)
			(stroke
				(width 0.1)
				(type default)
			)
			(layer "B.Fab")
		)
		(fp_line
			(start 0.12065 0.2794)
			(end 0.12065 0.3048)
			(stroke
				(width 0.1)
				(type default)
			)
			(layer "B.Fab")
		)
		(fp_line
			(start -0.12065 -0.2794)
			(end -0.12065 -0.3048)
			(stroke
				(width 0.1)
				(type default)
			)
			(layer "B.Fab")
		)
		(fp_line
			(start 0.12065 -0.2794)
			(end -0.12065 -0.2794)
			(stroke
				(width 0.1)
				(type default)
			)
			(layer "B.Fab")
		)
		(fp_line
			(start -0.67945 -0.3048)
			(end -0.67945 0.3048)
			(stroke
				(width 0.1)
				(type default)
			)
			(layer "B.Fab")
		)
		(fp_line
			(start -0.12065 -0.3048)
			(end -0.67945 -0.3048)
			(stroke
				(width 0.1)
				(type default)
			)
			(layer "B.Fab")
		)
		(fp_line
			(start 0.12065 -0.305054)
			(end 0.12065 -0.2794)
			(stroke
				(width 0.1)
				(type default)
			)
			(layer "B.Fab")
		)
		(fp_line
			(start 0.67945 -0.305054)
			(end 0.12065 -0.305054)
			(stroke
				(width 0.1)
				(type default)
			)
			(layer "B.Fab")
		)
		(pad "1" smd circle
			(at 0.40005 0 90)
			(size 0 0)
			(layers "B.Cu" "B.Mask" "B.Paste")
			(net "SMB_CPU0_CPU1_APML_MUX1_SCL")
		)
		(pad "2" smd circle
			(at -0.40005 0 90)
			(size 0 0)
			(layers "B.Cu" "B.Mask" "B.Paste")
			(net "SMB_APML_CPU1_R_SCL")
		)
	)
)
